(kicad_pcb
	(version 20260206)
	(generator "pcbnew")
	(generator_version "10.0")
	(general
		(thickness 1.6)
		(legacy_teardrops no)
	)
	(paper "A4")
	(title_block
		(title "03242023_DA0F0TMBIJ0_F0T_Motherboard_J_brd_V01_OCP.brd")
		(comment 1 "Grand Teton / footprints 4361-4366 of 6105")
	)
	(layers
		(0 "F.Cu" signal "TOP")
		(4 "In1.Cu" signal "GND")
		(6 "In2.Cu" signal "IN1")
		(8 "In3.Cu" signal "GND1")
		(10 "In4.Cu" signal "IN2")
		(12 "In5.Cu" signal "GND2")
		(14 "In6.Cu" signal "IN3")
		(16 "In7.Cu" signal "GND3")
		(18 "In8.Cu" signal "VCC")
		(20 "In9.Cu" signal "VCC1")
		(22 "In10.Cu" signal "GND4")
		(24 "In11.Cu" signal "IN4")
		(26 "In12.Cu" signal "GND5")
		(28 "In13.Cu" signal "IN5")
		(30 "In14.Cu" signal "GND6")
		(32 "In15.Cu" signal "IN6")
		(34 "In16.Cu" signal "GND7")
		(2 "B.Cu" signal "BOTTOM")
		(9 "F.Adhes" user "F.Adhesive")
		(11 "B.Adhes" user "B.Adhesive")
		(13 "F.Paste" user "Package Geometry/Pastemask Top")
		(15 "B.Paste" user "Package Geometry/Pastemask Bottom")
		(5 "F.SilkS" user "Ref Des/Silkscreen Top")
		(7 "B.SilkS" user "Ref Des/Silkscreen Bottom")
		(1 "F.Mask" user "Board Geometry/Soldermask Top")
		(3 "B.Mask" user "Board Geometry/Soldermask Bottom")
		(17 "Dwgs.User" user "User.Drawings")
		(19 "Cmts.User" user "User.Comments")
		(21 "Eco1.User" user "User.Eco1")
		(23 "Eco2.User" user "User.Eco2")
		(25 "Edge.Cuts" user "Board Geometry/Outline")
		(27 "Margin" user)
		(31 "F.CrtYd" user "Package Geometry/Place Bound Top")
		(29 "B.CrtYd" user "Package Geometry/Place Bound Bottom")
		(35 "F.Fab" user "Ref Des/Assembly Top")
		(33 "B.Fab" user "Ref Des/Assembly Bottom")
	)
	(footprint ""
		(layer "B.Cu")
		(at 107.77728 -356.504748 -90)
		(property "Reference" "PR4238"
			(at 0 0 90)
			(layer "B.SilkS")
			(hide yes)
			(effects
				(font
					(size 1.27 1.27)
				)
				(justify mirror)
			)
		)
		(property "Value" ""
			(at 0 0 90)
			(layer "B.Fab")
			(effects
				(font
					(size 1.27 1.27)
				)
				(justify mirror)
			)
		)
		(duplicate_pad_numbers_are_jumpers no)
		(fp_line
			(start -0.7874 0.4064)
			(end 0.7874 0.4064)
			(stroke
				(width 0.1524)
				(type default)
			)
			(layer "B.SilkS")
		)
		(fp_line
			(start 0.7874 0.4064)
			(end 0.7874 -0.4064)
			(stroke
				(width 0.1524)
				(type default)
			)
			(layer "B.SilkS")
		)
		(fp_line
			(start -0.7874 -0.4064)
			(end -0.7874 0.4064)
			(stroke
				(width 0.1524)
				(type default)
			)
			(layer "B.SilkS")
		)
		(fp_line
			(start 0.7874 -0.4064)
			(end -0.7874 -0.4064)
			(stroke
				(width 0.1524)
				(type default)
			)
			(layer "B.SilkS")
		)
		(fp_line
			(start -0.67945 0.3048)
			(end -0.120396 0.3048)
			(stroke
				(width 0.1)
				(type default)
			)
			(layer "B.Fab")
		)
		(fp_line
			(start -0.120396 0.3048)
			(end -0.120396 0.2794)
			(stroke
				(width 0.1)
				(type default)
			)
			(layer "B.Fab")
		)
		(fp_line
			(start 0.12065 0.3048)
			(end 0.67945 0.3048)
			(stroke
				(width 0.1)
				(type default)
			)
			(layer "B.Fab")
		)
		(fp_line
			(start 0.67945 0.3048)
			(end 0.67945 -0.305054)
			(stroke
				(width 0.1)
				(type default)
			)
			(layer "B.Fab")
		)
		(fp_line
			(start -0.120396 0.2794)
			(end 0.12065 0.2794)
			(stroke
				(width 0.1)
				(type default)
			)
			(layer "B.Fab")
		)
		(fp_line
			(start 0.12065 0.2794)
			(end 0.12065 0.3048)
			(stroke
				(width 0.1)
				(type default)
			)
			(layer "B.Fab")
		)
		(fp_line
			(start -0.12065 -0.2794)
			(end -0.12065 -0.3048)
			(stroke
				(width 0.1)
				(type default)
			)
			(layer "B.Fab")
		)
		(fp_line
			(start 0.12065 -0.2794)
			(end -0.12065 -0.2794)
			(stroke
				(width 0.1)
				(type default)
			)
			(layer "B.Fab")
		)
		(fp_line
			(start -0.67945 -0.3048)
			(end -0.67945 0.3048)
			(stroke
				(width 0.1)
				(type default)
			)
			(layer "B.Fab")
		)
		(fp_line
			(start -0.12065 -0.3048)
			(end -0.67945 -0.3048)
			(stroke
				(width 0.1)
				(type default)
			)
			(layer "B.Fab")
		)
		(fp_line
			(start 0.12065 -0.305054)
			(end 0.12065 -0.2794)
			(stroke
				(width 0.1)
				(type default)
			)
			(layer "B.Fab")
		)
		(fp_line
			(start 0.67945 -0.305054)
			(end 0.12065 -0.305054)
			(stroke
				(width 0.1)
				(type default)
			)
			(layer "B.Fab")
		)
		(pad "1" smd circle
			(at 0.40005 0 90)
			(size 0 0)
			(layers "B.Cu" "B.Mask" "B.Paste")
			(net "PVCCFA_EHV_FIVRA_CPU1_IMON4")
		)
		(pad "2" smd circle
			(at -0.40005 0 90)
			(size 0 0)
			(layers "B.Cu" "B.Mask" "B.Paste")
			(net "GND")
		)
	)
	(footprint ""
		(layer "B.Cu")
		(at 434.354478 -177.15611 -90)
		(property "Reference" "R2338"
			(at 0 0 90)
			(layer "B.SilkS")
			(hide yes)
			(effects
				(font
					(size 1.27 1.27)
				)
				(justify mirror)
			)
		)
		(property "Value" ""
			(at 0 0 90)
			(layer "B.Fab")
			(effects
				(font
					(size 1.27 1.27)
				)
				(justify mirror)
			)
		)
		(duplicate_pad_numbers_are_jumpers no)
		(fp_line
			(start -0.7874 0.4064)
			(end 0.7874 0.4064)
			(stroke
				(width 0.1524)
				(type default)
			)
			(layer "B.SilkS")
		)
		(fp_line
			(start 0.7874 0.4064)
			(end 0.7874 -0.4064)
			(stroke
				(width 0.1524)
				(type default)
			)
			(layer "B.SilkS")
		)
		(fp_line
			(start -0.7874 -0.4064)
			(end -0.7874 0.4064)
			(stroke
				(width 0.1524)
				(type default)
			)
			(layer "B.SilkS")
		)
		(fp_line
			(start 0.7874 -0.4064)
			(end -0.7874 -0.4064)
			(stroke
				(width 0.1524)
				(type default)
			)
			(layer "B.SilkS")
		)
		(fp_line
			(start -0.67945 0.3048)
			(end -0.120396 0.3048)
			(stroke
				(width 0.1)
				(type default)
			)
			(layer "B.Fab")
		)
		(fp_line
			(start -0.120396 0.3048)
			(end -0.120396 0.2794)
			(stroke
				(width 0.1)
				(type default)
			)
			(layer "B.Fab")
		)
		(fp_line
			(start 0.12065 0.3048)
			(end 0.67945 0.3048)
			(stroke
				(width 0.1)
				(type default)
			)
			(layer "B.Fab")
		)
		(fp_line
			(start 0.67945 0.3048)
			(end 0.67945 -0.305054)
			(stroke
				(width 0.1)
				(type default)
			)
			(layer "B.Fab")
		)
		(fp_line
			(start -0.120396 0.2794)
			(end 0.12065 0.2794)
			(stroke
				(width 0.1)
				(type default)
			)
			(layer "B.Fab")
		)
		(fp_line
			(start 0.12065 0.2794)
			(end 0.12065 0.3048)
			(stroke
				(width 0.1)
				(type default)
			)
			(layer "B.Fab")
		)
		(fp_line
			(start -0.12065 -0.2794)
			(end -0.12065 -0.3048)
			(stroke
				(width 0.1)
				(type default)
			)
			(layer "B.Fab")
		)
		(fp_line
			(start 0.12065 -0.2794)
			(end -0.12065 -0.2794)
			(stroke
				(width 0.1)
				(type default)
			)
			(layer "B.Fab")
		)
		(fp_line
			(start -0.67945 -0.3048)
			(end -0.67945 0.3048)
			(stroke
				(width 0.1)
				(type default)
			)
			(layer "B.Fab")
		)
		(fp_line
			(start -0.12065 -0.3048)
			(end -0.67945 -0.3048)
			(stroke
				(width 0.1)
				(type default)
			)
			(layer "B.Fab")
		)
		(fp_line
			(start 0.12065 -0.305054)
			(end 0.12065 -0.2794)
			(stroke
				(width 0.1)
				(type default)
			)
			(layer "B.Fab")
		)
		(fp_line
			(start 0.67945 -0.305054)
			(end 0.12065 -0.305054)
			(stroke
				(width 0.1)
				(type default)
			)
			(layer "B.Fab")
		)
		(pad "1" smd circle
			(at 0.40005 0 90)
			(size 0 0)
			(layers "B.Cu" "B.Mask" "B.Paste")
			(net "P3V3_AUX")
		)
		(pad "2" smd circle
			(at -0.40005 0 90)
			(size 0 0)
			(layers "B.Cu" "B.Mask" "B.Paste")
			(net "FM_PVNN_MAIN_CPU0_EN")
		)
	)
	(footprint ""
		(layer "B.Cu")
		(at 453.850756 -318.704976)
		(property "Reference" "R41"
			(at 0 0 0)
			(layer "B.SilkS")
			(hide yes)
			(effects
				(font
					(size 1.27 1.27)
				)
				(justify mirror)
			)
		)
		(property "Value" ""
			(at 0 0 0)
			(layer "B.Fab")
			(effects
				(font
					(size 1.27 1.27)
				)
				(justify mirror)
			)
		)
		(duplicate_pad_numbers_are_jumpers no)
		(fp_line
			(start -0.7874 -0.4064)
			(end -0.7874 0.4064)
			(stroke
				(width 0.1524)
				(type default)
			)
			(layer "B.SilkS")
		)
		(fp_line
			(start -0.7874 0.4064)
			(end 0.7874 0.4064)
			(stroke
				(width 0.1524)
				(type default)
			)
			(layer "B.SilkS")
		)
		(fp_line
			(start 0.7874 -0.4064)
			(end -0.7874 -0.4064)
			(stroke
				(width 0.1524)
				(type default)
			)
			(layer "B.SilkS")
		)
		(fp_line
			(start 0.7874 0.4064)
			(end 0.7874 -0.4064)
			(stroke
				(width 0.1524)
				(type default)
			)
			(layer "B.SilkS")
		)
		(fp_line
			(start -0.67945 -0.3048)
			(end -0.67945 0.3048)
			(stroke
				(width 0.1)
				(type default)
			)
			(layer "B.Fab")
		)
		(fp_line
			(start -0.67945 0.3048)
			(end -0.120396 0.3048)
			(stroke
				(width 0.1)
				(type default)
			)
			(layer "B.Fab")
		)
		(fp_line
			(start -0.12065 -0.3048)
			(end -0.67945 -0.3048)
			(stroke
				(width 0.1)
				(type default)
			)
			(layer "B.Fab")
		)
		(fp_line
			(start -0.12065 -0.2794)
			(end -0.12065 -0.3048)
			(stroke
				(width 0.1)
				(type default)
			)
			(layer "B.Fab")
		)
		(fp_line
			(start -0.120396 0.2794)
			(end 0.12065 0.2794)
			(stroke
				(width 0.1)
				(type default)
			)
			(layer "B.Fab")
		)
		(fp_line
			(start -0.120396 0.3048)
			(end -0.120396 0.2794)
			(stroke
				(width 0.1)
				(type default)
			)
			(layer "B.Fab")
		)
		(fp_line
			(start 0.12065 -0.305054)
			(end 0.12065 -0.2794)
			(stroke
				(width 0.1)
				(type default)
			)
			(layer "B.Fab")
		)
		(fp_line
			(start 0.12065 -0.2794)
			(end -0.12065 -0.2794)
			(stroke
				(width 0.1)
				(type default)
			)
			(layer "B.Fab")
		)
		(fp_line
			(start 0.12065 0.2794)
			(end 0.12065 0.3048)
			(stroke
				(width 0.1)
				(type default)
			)
			(layer "B.Fab")
		)
		(fp_line
			(start 0.12065 0.3048)
			(end 0.67945 0.3048)
			(stroke
				(width 0.1)
				(type default)
			)
			(layer "B.Fab")
		)
		(fp_line
			(start 0.67945 -0.305054)
			(end 0.12065 -0.305054)
			(stroke
				(width 0.1)
				(type default)
			)
			(layer "B.Fab")
		)
		(fp_line
			(start 0.67945 0.3048)
			(end 0.67945 -0.305054)
			(stroke
				(width 0.1)
				(type default)
			)
			(layer "B.Fab")
		)
		(pad "1" smd circle
			(at 0.40005 0 180)
			(size 0 0)
			(layers "B.Cu" "B.Mask" "B.Paste")
			(net "PD_CHH_CPU0_DIMM2_SAA")
		)
		(pad "2" smd circle
			(at -0.40005 0 180)
			(size 0 0)
			(layers "B.Cu" "B.Mask" "B.Paste")
			(net "GND")
		)
	)
	(footprint ""
		(layer "B.Cu")
		(at 336.167222 -33.20542 90)
		(property "Reference" "R916"
			(at 0 0 90)
			(layer "B.SilkS")
			(hide yes)
			(effects
				(font
					(size 1.27 1.27)
				)
				(justify mirror)
			)
		)
		(property "Value" ""
			(at 0 0 90)
			(layer "B.Fab")
			(effects
				(font
					(size 1.27 1.27)
				)
				(justify mirror)
			)
		)
		(duplicate_pad_numbers_are_jumpers no)
		(fp_line
			(start 0.7874 -0.4064)
			(end -0.7874 -0.4064)
			(stroke
				(width 0.1524)
				(type default)
			)
			(layer "B.SilkS")
		)
		(fp_line
			(start -0.7874 -0.4064)
			(end -0.7874 0.4064)
			(stroke
				(width 0.1524)
				(type default)
			)
			(layer "B.SilkS")
		)
		(fp_line
			(start 0.7874 0.4064)
			(end 0.7874 -0.4064)
			(stroke
				(width 0.1524)
				(type default)
			)
			(layer "B.SilkS")
		)
		(fp_line
			(start -0.7874 0.4064)
			(end 0.7874 0.4064)
			(stroke
				(width 0.1524)
				(type default)
			)
			(layer "B.SilkS")
		)
		(fp_line
			(start 0.67945 -0.305054)
			(end 0.12065 -0.305054)
			(stroke
				(width 0.1)
				(type default)
			)
			(layer "B.Fab")
		)
		(fp_line
			(start 0.12065 -0.305054)
			(end 0.12065 -0.2794)
			(stroke
				(width 0.1)
				(type default)
			)
			(layer "B.Fab")
		)
		(fp_line
			(start -0.12065 -0.3048)
			(end -0.67945 -0.3048)
			(stroke
				(width 0.1)
				(type default)
			)
			(layer "B.Fab")
		)
		(fp_line
			(start -0.67945 -0.3048)
			(end -0.67945 0.3048)
			(stroke
				(width 0.1)
				(type default)
			)
			(layer "B.Fab")
		)
		(fp_line
			(start 0.12065 -0.2794)
			(end -0.12065 -0.2794)
			(stroke
				(width 0.1)
				(type default)
			)
			(layer "B.Fab")
		)
		(fp_line
			(start -0.12065 -0.2794)
			(end -0.12065 -0.3048)
			(stroke
				(width 0.1)
				(type default)
			)
			(layer "B.Fab")
		)
		(fp_line
			(start 0.12065 0.2794)
			(end 0.12065 0.3048)
			(stroke
				(width 0.1)
				(type default)
			)
			(layer "B.Fab")
		)
		(fp_line
			(start -0.120396 0.2794)
			(end 0.12065 0.2794)
			(stroke
				(width 0.1)
				(type default)
			)
			(layer "B.Fab")
		)
		(fp_line
			(start 0.67945 0.3048)
			(end 0.67945 -0.305054)
			(stroke
				(width 0.1)
				(type default)
			)
			(layer "B.Fab")
		)
		(fp_line
			(start 0.12065 0.3048)
			(end 0.67945 0.3048)
			(stroke
				(width 0.1)
				(type default)
			)
			(layer "B.Fab")
		)
		(fp_line
			(start -0.120396 0.3048)
			(end -0.120396 0.2794)
			(stroke
				(width 0.1)
				(type default)
			)
			(layer "B.Fab")
		)
		(fp_line
			(start -0.67945 0.3048)
			(end -0.120396 0.3048)
			(stroke
				(width 0.1)
				(type default)
			)
			(layer "B.Fab")
		)
		(pad "1" smd circle
			(at 0.40005 0 270)
			(size 0 0)
			(layers "B.Cu" "B.Mask" "B.Paste")
			(net "SPI_PCH_IO1")
		)
		(pad "2" smd circle
			(at -0.40005 0 270)
			(size 0 0)
			(layers "B.Cu" "B.Mask" "B.Paste")
			(net "SPI_SYS_MISO")
		)
	)
	(footprint ""
		(layer "B.Cu")
		(at 326.00519 -28.84297 -90)
		(property "Reference" "R613"
			(at 0 0 90)
			(layer "B.SilkS")
			(hide yes)
			(effects
				(font
					(size 1.27 1.27)
				)
				(justify mirror)
			)
		)
		(property "Value" ""
			(at 0 0 90)
			(layer "B.Fab")
			(effects
				(font
					(size 1.27 1.27)
				)
				(justify mirror)
			)
		)
		(duplicate_pad_numbers_are_jumpers no)
		(fp_line
			(start -0.7874 0.4064)
			(end 0.7874 0.4064)
			(stroke
				(width 0.1524)
				(type default)
			)
			(layer "B.SilkS")
		)
		(fp_line
			(start 0.7874 0.4064)
			(end 0.7874 -0.4064)
			(stroke
				(width 0.1524)
				(type default)
			)
			(layer "B.SilkS")
		)
		(fp_line
			(start -0.7874 -0.4064)
			(end -0.7874 0.4064)
			(stroke
				(width 0.1524)
				(type default)
			)
			(layer "B.SilkS")
		)
		(fp_line
			(start 0.7874 -0.4064)
			(end -0.7874 -0.4064)
			(stroke
				(width 0.1524)
				(type default)
			)
			(layer "B.SilkS")
		)
		(fp_line
			(start -0.67945 0.3048)
			(end -0.120396 0.3048)
			(stroke
				(width 0.1)
				(type default)
			)
			(layer "B.Fab")
		)
		(fp_line
			(start -0.120396 0.3048)
			(end -0.120396 0.2794)
			(stroke
				(width 0.1)
				(type default)
			)
			(layer "B.Fab")
		)
		(fp_line
			(start 0.12065 0.3048)
			(end 0.67945 0.3048)
			(stroke
				(width 0.1)
				(type default)
			)
			(layer "B.Fab")
		)
		(fp_line
			(start 0.67945 0.3048)
			(end 0.67945 -0.305054)
			(stroke
				(width 0.1)
				(type default)
			)
			(layer "B.Fab")
		)
		(fp_line
			(start -0.120396 0.2794)
			(end 0.12065 0.2794)
			(stroke
				(width 0.1)
				(type default)
			)
			(layer "B.Fab")
		)
		(fp_line
			(start 0.12065 0.2794)
			(end 0.12065 0.3048)
			(stroke
				(width 0.1)
				(type default)
			)
			(layer "B.Fab")
		)
		(fp_line
			(start -0.12065 -0.2794)
			(end -0.12065 -0.3048)
			(stroke
				(width 0.1)
				(type default)
			)
			(layer "B.Fab")
		)
		(fp_line
			(start 0.12065 -0.2794)
			(end -0.12065 -0.2794)
			(stroke
				(width 0.1)
				(type default)
			)
			(layer "B.Fab")
		)
		(fp_line
			(start -0.67945 -0.3048)
			(end -0.67945 0.3048)
			(stroke
				(width 0.1)
				(type default)
			)
			(layer "B.Fab")
		)
		(fp_line
			(start -0.12065 -0.3048)
			(end -0.67945 -0.3048)
			(stroke
				(width 0.1)
				(type default)
			)
			(layer "B.Fab")
		)
		(fp_line
			(start 0.12065 -0.305054)
			(end 0.12065 -0.2794)
			(stroke
				(width 0.1)
				(type default)
			)
			(layer "B.Fab")
		)
		(fp_line
			(start 0.67945 -0.305054)
			(end 0.12065 -0.305054)
			(stroke
				(width 0.1)
				(type default)
			)
			(layer "B.Fab")
		)
		(pad "1" smd circle
			(at 0.40005 0 90)
			(size 0 0)
			(layers "B.Cu" "B.Mask" "B.Paste")
			(net "P3V3_AUX")
		)
		(pad "2" smd circle
			(at -0.40005 0 90)
			(size 0 0)
			(layers "B.Cu" "B.Mask" "B.Paste")
			(net "FM_JTAG_ODT_DISABLE")
		)
	)
	(footprint ""
		(layer "B.Cu")
		(at 180.26888 -124.170948 180)
		(property "Reference" "C1936"
			(at 0 0 0)
			(layer "B.SilkS")
			(hide yes)
			(effects
				(font
					(size 1.27 1.27)
				)
				(justify mirror)
			)
		)
		(property "Value" ""
			(at 0 0 0)
			(layer "B.Fab")
			(effects
				(font
					(size 1.27 1.27)
				)
				(justify mirror)
			)
		)
		(duplicate_pad_numbers_are_jumpers no)
		(fp_line
			(start 0.7874 0.4064)
			(end 0.7874 -0.4064)
			(stroke
				(width 0.1524)
				(type default)
			)
			(layer "B.SilkS")
		)
		(fp_line
			(start 0.7874 -0.4064)
			(end -0.7874 -0.4064)
			(stroke
				(width 0.1524)
				(type default)
			)
			(layer "B.SilkS")
		)
		(fp_line
			(start -0.7874 0.4064)
			(end 0.7874 0.4064)
			(stroke
				(width 0.1524)
				(type default)
			)
			(layer "B.SilkS")
		)
		(fp_line
			(start -0.7874 -0.4064)
			(end -0.7874 0.4064)
			(stroke
				(width 0.1524)
				(type default)
			)
			(layer "B.SilkS")
		)
		(fp_line
			(start 0.67945 0.3048)
			(end 0.67945 -0.305054)
			(stroke
				(width 0.1)
				(type default)
			)
			(layer "B.Fab")
		)
		(fp_line
			(start 0.67945 -0.305054)
			(end 0.12065 -0.305054)
			(stroke
				(width 0.1)
				(type default)
			)
			(layer "B.Fab")
		)
		(fp_line
			(start 0.12065 0.3048)
			(end 0.67945 0.3048)
			(stroke
				(width 0.1)
				(type default)
			)
			(layer "B.Fab")
		)
		(fp_line
			(start 0.12065 0.2794)
			(end 0.12065 0.3048)
			(stroke
				(width 0.1)
				(type default)
			)
			(layer "B.Fab")
		)
		(fp_line
			(start 0.12065 -0.2794)
			(end -0.12065 -0.2794)
			(stroke
				(width 0.1)
				(type default)
			)
			(layer "B.Fab")
		)
		(fp_line
			(start 0.12065 -0.305054)
			(end 0.12065 -0.2794)
			(stroke
				(width 0.1)
				(type default)
			)
			(layer "B.Fab")
		)
		(fp_line
			(start -0.120396 0.3048)
			(end -0.120396 0.2794)
			(stroke
				(width 0.1)
				(type default)
			)
			(layer "B.Fab")
		)
		(fp_line
			(start -0.120396 0.2794)
			(end 0.12065 0.2794)
			(stroke
				(width 0.1)
				(type default)
			)
			(layer "B.Fab")
		)
		(fp_line
			(start -0.12065 -0.2794)
			(end -0.12065 -0.3048)
			(stroke
				(width 0.1)
				(type default)
			)
			(layer "B.Fab")
		)
		(fp_line
			(start -0.12065 -0.3048)
			(end -0.67945 -0.3048)
			(stroke
				(width 0.1)
				(type default)
			)
			(layer "B.Fab")
		)
		(fp_line
			(start -0.67945 0.3048)
			(end -0.120396 0.3048)
			(stroke
				(width 0.1)
				(type default)
			)
			(layer "B.Fab")
		)
		(fp_line
			(start -0.67945 -0.3048)
			(end -0.67945 0.3048)
			(stroke
				(width 0.1)
				(type default)
			)
			(layer "B.Fab")
		)
		(pad "1" smd circle
			(at 0.40005 0)
			(size 0 0)
			(layers "B.Cu" "B.Mask" "B.Paste")
			(net "VCC_PLD_CORE")
		)
		(pad "2" smd circle
			(at -0.40005 0)
			(size 0 0)
			(layers "B.Cu" "B.Mask" "B.Paste")
			(net "GND")
		)
	)
)
